(kicad_pcb
	(version 20260206)
	(generator "pcbnew")
	(generator_version "10.0")
	(general
		(thickness 1.6)
		(legacy_teardrops no)
	)
	(paper "A4")
	(title_block
		(title "04192023_DAF0TMB3IC0_F0TG_MB_C_brd_V02_OCP.brd")
		(comment 1 "Grand Teton / footprints 1663-1668 of 8354")
	)
	(layers
		(0 "F.Cu" signal "TOP")
		(4 "In1.Cu" signal "GND")
		(6 "In2.Cu" signal "IN1")
		(8 "In3.Cu" signal "GND1")
		(10 "In4.Cu" signal "IN2")
		(12 "In5.Cu" signal "GND2")
		(14 "In6.Cu" signal "IN3")
		(16 "In7.Cu" signal "GND3")
		(18 "In8.Cu" signal "VCC")
		(20 "In9.Cu" signal "VCC1")
		(22 "In10.Cu" signal "GND4")
		(24 "In11.Cu" signal "IN4")
		(26 "In12.Cu" signal "GND5")
		(28 "In13.Cu" signal "IN5")
		(30 "In14.Cu" signal "GND6")
		(32 "In15.Cu" signal "IN6")
		(34 "In16.Cu" signal "GND7")
		(2 "B.Cu" signal "BOTTOM")
		(9 "F.Adhes" user "F.Adhesive")
		(11 "B.Adhes" user "B.Adhesive")
		(13 "F.Paste" user "Package Geometry/Pastemask Top")
		(15 "B.Paste" user "Package Geometry/Pastemask Bottom")
		(5 "F.SilkS" user "Ref Des/Silkscreen Top")
		(7 "B.SilkS" user "Ref Des/Silkscreen Bottom")
		(1 "F.Mask" user "Board Geometry/Soldermask Top")
		(3 "B.Mask" user "Board Geometry/Soldermask Bottom")
		(17 "Dwgs.User" user "User.Drawings")
		(19 "Cmts.User" user "User.Comments")
		(21 "Eco1.User" user "User.Eco1")
		(23 "Eco2.User" user "User.Eco2")
		(25 "Edge.Cuts" user "Board Geometry/Outline")
		(27 "Margin" user)
		(31 "F.CrtYd" user "Package Geometry/Place Bound Top")
		(29 "B.CrtYd" user "Package Geometry/Place Bound Bottom")
		(35 "F.Fab" user "Ref Des/Assembly Top")
		(33 "B.Fab" user "Ref Des/Assembly Bottom")
	)
	(footprint ""
		(layer "F.Cu")
		(at 75.081638 -334.991202 -90)
		(property "Reference" "PC372_C1P1_2"
			(at 0 0 270)
			(layer "F.SilkS")
			(hide yes)
			(effects
				(font
					(size 1.27 1.27)
				)
			)
		)
		(property "Value" ""
			(at 0 0 270)
			(layer "F.Fab")
			(effects
				(font
					(size 1.27 1.27)
				)
			)
		)
		(duplicate_pad_numbers_are_jumpers no)
		(fp_line
			(start -0.7874 0.4064)
			(end -0.7874 -0.4064)
			(stroke
				(width 0.1524)
				(type default)
			)
			(layer "F.SilkS")
		)
		(fp_line
			(start 0.7874 0.4064)
			(end -0.7874 0.4064)
			(stroke
				(width 0.1524)
				(type default)
			)
			(layer "F.SilkS")
		)
		(fp_line
			(start -0.7874 -0.4064)
			(end 0.7874 -0.4064)
			(stroke
				(width 0.1524)
				(type default)
			)
			(layer "F.SilkS")
		)
		(fp_line
			(start 0.7874 -0.4064)
			(end 0.7874 0.4064)
			(stroke
				(width 0.1524)
				(type default)
			)
			(layer "F.SilkS")
		)
		(fp_line
			(start -0.67945 0.3048)
			(end -0.67945 -0.305054)
			(stroke
				(width 0.1)
				(type default)
			)
			(layer "F.Fab")
		)
		(fp_line
			(start -0.12065 0.3048)
			(end -0.67945 0.3048)
			(stroke
				(width 0.1)
				(type default)
			)
			(layer "F.Fab")
		)
		(fp_line
			(start 0.120396 0.3048)
			(end 0.120396 0.2794)
			(stroke
				(width 0.1)
				(type default)
			)
			(layer "F.Fab")
		)
		(fp_line
			(start 0.67945 0.3048)
			(end 0.120396 0.3048)
			(stroke
				(width 0.1)
				(type default)
			)
			(layer "F.Fab")
		)
		(fp_line
			(start -0.12065 0.2794)
			(end -0.12065 0.3048)
			(stroke
				(width 0.1)
				(type default)
			)
			(layer "F.Fab")
		)
		(fp_line
			(start 0.120396 0.2794)
			(end -0.12065 0.2794)
			(stroke
				(width 0.1)
				(type default)
			)
			(layer "F.Fab")
		)
		(fp_line
			(start -0.12065 -0.2794)
			(end 0.12065 -0.2794)
			(stroke
				(width 0.1)
				(type default)
			)
			(layer "F.Fab")
		)
		(fp_line
			(start 0.12065 -0.2794)
			(end 0.12065 -0.3048)
			(stroke
				(width 0.1)
				(type default)
			)
			(layer "F.Fab")
		)
		(fp_line
			(start 0.12065 -0.3048)
			(end 0.67945 -0.3048)
			(stroke
				(width 0.1)
				(type default)
			)
			(layer "F.Fab")
		)
		(fp_line
			(start 0.67945 -0.3048)
			(end 0.67945 0.3048)
			(stroke
				(width 0.1)
				(type default)
			)
			(layer "F.Fab")
		)
		(fp_line
			(start -0.67945 -0.305054)
			(end -0.12065 -0.305054)
			(stroke
				(width 0.1)
				(type default)
			)
			(layer "F.Fab")
		)
		(fp_line
			(start -0.12065 -0.305054)
			(end -0.12065 -0.2794)
			(stroke
				(width 0.1)
				(type default)
			)
			(layer "F.Fab")
		)
		(pad "1" smd circle
			(at -0.40005 0 270)
			(size 0 0)
			(layers "F.Cu" "F.Mask" "F.Paste")
			(net "PVDDCR_CPU1_P1_PVCC")
		)
		(pad "2" smd circle
			(at 0.40005 0 270)
			(size 0 0)
			(layers "F.Cu" "F.Mask" "F.Paste")
			(net "GND")
		)
	)
	(footprint ""
		(layer "F.Cu")
		(at 265.49223 -103.272844 180)
		(property "Reference" "C1508"
			(at 0 0 180)
			(layer "F.SilkS")
			(hide yes)
			(effects
				(font
					(size 1.27 1.27)
				)
			)
		)
		(property "Value" ""
			(at 0 0 180)
			(layer "F.Fab")
			(effects
				(font
					(size 1.27 1.27)
				)
			)
		)
		(duplicate_pad_numbers_are_jumpers no)
		(fp_line
			(start 0.7874 0.4064)
			(end -0.7874 0.4064)
			(stroke
				(width 0.1524)
				(type default)
			)
			(layer "F.SilkS")
		)
		(fp_line
			(start 0.7874 -0.4064)
			(end 0.7874 0.4064)
			(stroke
				(width 0.1524)
				(type default)
			)
			(layer "F.SilkS")
		)
		(fp_line
			(start -0.7874 0.4064)
			(end -0.7874 -0.4064)
			(stroke
				(width 0.1524)
				(type default)
			)
			(layer "F.SilkS")
		)
		(fp_line
			(start -0.7874 -0.4064)
			(end 0.7874 -0.4064)
			(stroke
				(width 0.1524)
				(type default)
			)
			(layer "F.SilkS")
		)
		(fp_line
			(start 0.67945 0.3048)
			(end 0.120396 0.3048)
			(stroke
				(width 0.1)
				(type default)
			)
			(layer "F.Fab")
		)
		(fp_line
			(start 0.67945 -0.3048)
			(end 0.67945 0.3048)
			(stroke
				(width 0.1)
				(type default)
			)
			(layer "F.Fab")
		)
		(fp_line
			(start 0.12065 -0.2794)
			(end 0.12065 -0.3048)
			(stroke
				(width 0.1)
				(type default)
			)
			(layer "F.Fab")
		)
		(fp_line
			(start 0.12065 -0.3048)
			(end 0.67945 -0.3048)
			(stroke
				(width 0.1)
				(type default)
			)
			(layer "F.Fab")
		)
		(fp_line
			(start 0.120396 0.3048)
			(end 0.120396 0.2794)
			(stroke
				(width 0.1)
				(type default)
			)
			(layer "F.Fab")
		)
		(fp_line
			(start 0.120396 0.2794)
			(end -0.12065 0.2794)
			(stroke
				(width 0.1)
				(type default)
			)
			(layer "F.Fab")
		)
		(fp_line
			(start -0.12065 0.3048)
			(end -0.67945 0.3048)
			(stroke
				(width 0.1)
				(type default)
			)
			(layer "F.Fab")
		)
		(fp_line
			(start -0.12065 0.2794)
			(end -0.12065 0.3048)
			(stroke
				(width 0.1)
				(type default)
			)
			(layer "F.Fab")
		)
		(fp_line
			(start -0.12065 -0.2794)
			(end 0.12065 -0.2794)
			(stroke
				(width 0.1)
				(type default)
			)
			(layer "F.Fab")
		)
		(fp_line
			(start -0.12065 -0.305054)
			(end -0.12065 -0.2794)
			(stroke
				(width 0.1)
				(type default)
			)
			(layer "F.Fab")
		)
		(fp_line
			(start -0.67945 0.3048)
			(end -0.67945 -0.305054)
			(stroke
				(width 0.1)
				(type default)
			)
			(layer "F.Fab")
		)
		(fp_line
			(start -0.67945 -0.305054)
			(end -0.12065 -0.305054)
			(stroke
				(width 0.1)
				(type default)
			)
			(layer "F.Fab")
		)
		(pad "1" smd circle
			(at -0.40005 0 180)
			(size 0 0)
			(layers "F.Cu" "F.Mask" "F.Paste")
			(net "PVDD18_S5_P0")
		)
		(pad "2" smd circle
			(at 0.40005 0 180)
			(size 0 0)
			(layers "F.Cu" "F.Mask" "F.Paste")
			(net "GND")
		)
	)
	(footprint ""
		(layer "F.Cu")
		(at 33.198054 -346.719398 -90)
		(property "Reference" "PC619_IOP1_3"
			(at 0 0 270)
			(layer "F.SilkS")
			(hide yes)
			(effects
				(font
					(size 1.27 1.27)
				)
			)
		)
		(property "Value" ""
			(at 0 0 270)
			(layer "F.Fab")
			(effects
				(font
					(size 1.27 1.27)
				)
			)
		)
		(duplicate_pad_numbers_are_jumpers no)
		(fp_line
			(start -0.7874 0.4064)
			(end -0.7874 -0.4064)
			(stroke
				(width 0.1524)
				(type default)
			)
			(layer "F.SilkS")
		)
		(fp_line
			(start 0.7874 0.4064)
			(end -0.7874 0.4064)
			(stroke
				(width 0.1524)
				(type default)
			)
			(layer "F.SilkS")
		)
		(fp_line
			(start -0.7874 -0.4064)
			(end 0.7874 -0.4064)
			(stroke
				(width 0.1524)
				(type default)
			)
			(layer "F.SilkS")
		)
		(fp_line
			(start 0.7874 -0.4064)
			(end 0.7874 0.4064)
			(stroke
				(width 0.1524)
				(type default)
			)
			(layer "F.SilkS")
		)
		(fp_line
			(start -0.67945 0.3048)
			(end -0.67945 -0.305054)
			(stroke
				(width 0.1)
				(type default)
			)
			(layer "F.Fab")
		)
		(fp_line
			(start -0.12065 0.3048)
			(end -0.67945 0.3048)
			(stroke
				(width 0.1)
				(type default)
			)
			(layer "F.Fab")
		)
		(fp_line
			(start 0.120396 0.3048)
			(end 0.120396 0.2794)
			(stroke
				(width 0.1)
				(type default)
			)
			(layer "F.Fab")
		)
		(fp_line
			(start 0.67945 0.3048)
			(end 0.120396 0.3048)
			(stroke
				(width 0.1)
				(type default)
			)
			(layer "F.Fab")
		)
		(fp_line
			(start -0.12065 0.2794)
			(end -0.12065 0.3048)
			(stroke
				(width 0.1)
				(type default)
			)
			(layer "F.Fab")
		)
		(fp_line
			(start 0.120396 0.2794)
			(end -0.12065 0.2794)
			(stroke
				(width 0.1)
				(type default)
			)
			(layer "F.Fab")
		)
		(fp_line
			(start -0.12065 -0.2794)
			(end 0.12065 -0.2794)
			(stroke
				(width 0.1)
				(type default)
			)
			(layer "F.Fab")
		)
		(fp_line
			(start 0.12065 -0.2794)
			(end 0.12065 -0.3048)
			(stroke
				(width 0.1)
				(type default)
			)
			(layer "F.Fab")
		)
		(fp_line
			(start 0.12065 -0.3048)
			(end 0.67945 -0.3048)
			(stroke
				(width 0.1)
				(type default)
			)
			(layer "F.Fab")
		)
		(fp_line
			(start 0.67945 -0.3048)
			(end 0.67945 0.3048)
			(stroke
				(width 0.1)
				(type default)
			)
			(layer "F.Fab")
		)
		(fp_line
			(start -0.67945 -0.305054)
			(end -0.12065 -0.305054)
			(stroke
				(width 0.1)
				(type default)
			)
			(layer "F.Fab")
		)
		(fp_line
			(start -0.12065 -0.305054)
			(end -0.12065 -0.2794)
			(stroke
				(width 0.1)
				(type default)
			)
			(layer "F.Fab")
		)
		(pad "1" smd circle
			(at -0.40005 0 270)
			(size 0 0)
			(layers "F.Cu" "F.Mask" "F.Paste")
			(net "PVDDCR_CPU1_P1_PVCC")
		)
		(pad "2" smd circle
			(at 0.40005 0 270)
			(size 0 0)
			(layers "F.Cu" "F.Mask" "F.Paste")
			(net "GND")
		)
	)
	(footprint ""
		(layer "F.Cu")
		(at 422.55694 -101.270308 -90)
		(property "Reference" "PR3844"
			(at 0 0 270)
			(layer "F.SilkS")
			(hide yes)
			(effects
				(font
					(size 1.27 1.27)
				)
			)
		)
		(property "Value" ""
			(at 0 0 270)
			(layer "F.Fab")
			(effects
				(font
					(size 1.27 1.27)
				)
			)
		)
		(duplicate_pad_numbers_are_jumpers no)
		(fp_line
			(start -0.7874 0.4064)
			(end -0.7874 -0.4064)
			(stroke
				(width 0.1524)
				(type default)
			)
			(layer "F.SilkS")
		)
		(fp_line
			(start 0.7874 0.4064)
			(end -0.7874 0.4064)
			(stroke
				(width 0.1524)
				(type default)
			)
			(layer "F.SilkS")
		)
		(fp_line
			(start -0.7874 -0.4064)
			(end 0.7874 -0.4064)
			(stroke
				(width 0.1524)
				(type default)
			)
			(layer "F.SilkS")
		)
		(fp_line
			(start 0.7874 -0.4064)
			(end 0.7874 0.4064)
			(stroke
				(width 0.1524)
				(type default)
			)
			(layer "F.SilkS")
		)
		(fp_line
			(start -0.67945 0.3048)
			(end -0.67945 -0.305054)
			(stroke
				(width 0.1)
				(type default)
			)
			(layer "F.Fab")
		)
		(fp_line
			(start -0.12065 0.3048)
			(end -0.67945 0.3048)
			(stroke
				(width 0.1)
				(type default)
			)
			(layer "F.Fab")
		)
		(fp_line
			(start 0.120396 0.3048)
			(end 0.120396 0.2794)
			(stroke
				(width 0.1)
				(type default)
			)
			(layer "F.Fab")
		)
		(fp_line
			(start 0.67945 0.3048)
			(end 0.120396 0.3048)
			(stroke
				(width 0.1)
				(type default)
			)
			(layer "F.Fab")
		)
		(fp_line
			(start -0.12065 0.2794)
			(end -0.12065 0.3048)
			(stroke
				(width 0.1)
				(type default)
			)
			(layer "F.Fab")
		)
		(fp_line
			(start 0.120396 0.2794)
			(end -0.12065 0.2794)
			(stroke
				(width 0.1)
				(type default)
			)
			(layer "F.Fab")
		)
		(fp_line
			(start -0.12065 -0.2794)
			(end 0.12065 -0.2794)
			(stroke
				(width 0.1)
				(type default)
			)
			(layer "F.Fab")
		)
		(fp_line
			(start 0.12065 -0.2794)
			(end 0.12065 -0.3048)
			(stroke
				(width 0.1)
				(type default)
			)
			(layer "F.Fab")
		)
		(fp_line
			(start 0.12065 -0.3048)
			(end 0.67945 -0.3048)
			(stroke
				(width 0.1)
				(type default)
			)
			(layer "F.Fab")
		)
		(fp_line
			(start 0.67945 -0.3048)
			(end 0.67945 0.3048)
			(stroke
				(width 0.1)
				(type default)
			)
			(layer "F.Fab")
		)
		(fp_line
			(start -0.67945 -0.305054)
			(end -0.12065 -0.305054)
			(stroke
				(width 0.1)
				(type default)
			)
			(layer "F.Fab")
		)
		(fp_line
			(start -0.12065 -0.305054)
			(end -0.12065 -0.2794)
			(stroke
				(width 0.1)
				(type default)
			)
			(layer "F.Fab")
		)
		(pad "1" smd circle
			(at -0.40005 0 270)
			(size 0 0)
			(layers "F.Cu" "F.Mask" "F.Paste")
			(net "P3V3_OCP_MODE_1")
		)
		(pad "2" smd circle
			(at 0.40005 0 270)
			(size 0 0)
			(layers "F.Cu" "F.Mask" "F.Paste")
			(net "GND")
		)
	)
	(footprint ""
		(layer "F.Cu")
		(at 426.979588 -391.49909 180)
		(property "Reference" "R1059"
			(at 0 0 180)
			(layer "F.SilkS")
			(hide yes)
			(effects
				(font
					(size 1.27 1.27)
				)
			)
		)
		(property "Value" ""
			(at 0 0 180)
			(layer "F.Fab")
			(effects
				(font
					(size 1.27 1.27)
				)
			)
		)
		(duplicate_pad_numbers_are_jumpers no)
		(fp_line
			(start 0.32512 0.175006)
			(end -0.32512 0.175006)
			(stroke
				(width 0.1)
				(type default)
			)
			(layer "F.Fab")
		)
		(fp_line
			(start 0.32512 -0.175006)
			(end 0.32512 0.175006)
			(stroke
				(width 0.1)
				(type default)
			)
			(layer "F.Fab")
		)
		(fp_line
			(start -0.32512 0.175006)
			(end -0.32512 -0.175006)
			(stroke
				(width 0.1)
				(type default)
			)
			(layer "F.Fab")
		)
		(fp_line
			(start -0.32512 -0.175006)
			(end 0.32512 -0.175006)
			(stroke
				(width 0.1)
				(type default)
			)
			(layer "F.Fab")
		)
		(pad "1" smd rect
			(at -0.2667 0 180)
			(size 0.3048 0.381)
			(layers "F.Cu" "F.Mask" "F.Paste")
			(net "P1V8_CPU0_RT_1D")
		)
		(pad "2" smd rect
			(at 0.2667 0)
			(size 0.3048 0.381)
			(layers "F.Cu" "F.Mask" "F.Paste")
			(net "RT_CPU0_P2_ADDR1")
		)
	)
	(footprint ""
		(layer "F.Cu")
		(at 171.20743 -101.998018)
		(property "Reference" "R6184"
			(at 0 0 0)
			(layer "F.SilkS")
			(hide yes)
			(effects
				(font
					(size 1.27 1.27)
				)
			)
		)
		(property "Value" ""
			(at 0 0 0)
			(layer "F.Fab")
			(effects
				(font
					(size 1.27 1.27)
				)
			)
		)
		(duplicate_pad_numbers_are_jumpers no)
		(fp_line
			(start -0.7874 -0.4064)
			(end 0.7874 -0.4064)
			(stroke
				(width 0.1524)
				(type default)
			)
			(layer "F.SilkS")
		)
		(fp_line
			(start -0.7874 0.4064)
			(end -0.7874 -0.4064)
			(stroke
				(width 0.1524)
				(type default)
			)
			(layer "F.SilkS")
		)
		(fp_line
			(start 0.7874 -0.4064)
			(end 0.7874 0.4064)
			(stroke
				(width 0.1524)
				(type default)
			)
			(layer "F.SilkS")
		)
		(fp_line
			(start 0.7874 0.4064)
			(end -0.7874 0.4064)
			(stroke
				(width 0.1524)
				(type default)
			)
			(layer "F.SilkS")
		)
		(fp_line
			(start -0.67945 -0.305054)
			(end -0.12065 -0.305054)
			(stroke
				(width 0.1)
				(type default)
			)
			(layer "F.Fab")
		)
		(fp_line
			(start -0.67945 0.3048)
			(end -0.67945 -0.305054)
			(stroke
				(width 0.1)
				(type default)
			)
			(layer "F.Fab")
		)
		(fp_line
			(start -0.12065 -0.305054)
			(end -0.12065 -0.2794)
			(stroke
				(width 0.1)
				(type default)
			)
			(layer "F.Fab")
		)
		(fp_line
			(start -0.12065 -0.2794)
			(end 0.12065 -0.2794)
			(stroke
				(width 0.1)
				(type default)
			)
			(layer "F.Fab")
		)
		(fp_line
			(start -0.12065 0.2794)
			(end -0.12065 0.3048)
			(stroke
				(width 0.1)
				(type default)
			)
			(layer "F.Fab")
		)
		(fp_line
			(start -0.12065 0.3048)
			(end -0.67945 0.3048)
			(stroke
				(width 0.1)
				(type default)
			)
			(layer "F.Fab")
		)
		(fp_line
			(start 0.120396 0.2794)
			(end -0.12065 0.2794)
			(stroke
				(width 0.1)
				(type default)
			)
			(layer "F.Fab")
		)
		(fp_line
			(start 0.120396 0.3048)
			(end 0.120396 0.2794)
			(stroke
				(width 0.1)
				(type default)
			)
			(layer "F.Fab")
		)
		(fp_line
			(start 0.12065 -0.3048)
			(end 0.67945 -0.3048)
			(stroke
				(width 0.1)
				(type default)
			)
			(layer "F.Fab")
		)
		(fp_line
			(start 0.12065 -0.2794)
			(end 0.12065 -0.3048)
			(stroke
				(width 0.1)
				(type default)
			)
			(layer "F.Fab")
		)
		(fp_line
			(start 0.67945 -0.3048)
			(end 0.67945 0.3048)
			(stroke
				(width 0.1)
				(type default)
			)
			(layer "F.Fab")
		)
		(fp_line
			(start 0.67945 0.3048)
			(end 0.120396 0.3048)
			(stroke
				(width 0.1)
				(type default)
			)
			(layer "F.Fab")
		)
		(pad "1" smd circle
			(at -0.40005 0)
			(size 0 0)
			(layers "F.Cu" "F.Mask" "F.Paste")
			(net "FM_SEC_MUX_SEL")
		)
		(pad "2" smd circle
			(at 0.40005 0)
			(size 0 0)
			(layers "F.Cu" "F.Mask" "F.Paste")
			(net "FM_SEC_MUX_R_SEL")
		)
	)
)
